# T6G (Grand Teton) — schematic netlist excerpt (pin names and nets, part order shuffled) for the footprints in the layout excerpt that follows; sources: Cadence DE-HDL packaged netlist, KiCad conversion of 04192023_DAF0TMB3IC0_F0TG_MB_C_brd_V02_OCP.brd

J27  SCONN288_DDR506112002KQ  IO  pkg DDR288S_1-1VXC  page 105
  VIN_BULK0  = P12V_MEM_CPU1
  RFU0  = NC
  VIN_MGMT  = P3V3_AUX
  HSCL  = I3C_SPD_DDRH_CPU1_SCL
  HSDA  = I3C_SPD_DDRH_CPU1_SDA
  VSS0  = GND
  DQ0_A  = M_H_CPU1_SA_DQ<0>
  VSS1  = GND
  DQ1_A  = M_H_CPU1_SA_DQ<1>
  VSS2  = GND
  DQS0_A_T  = M_H_CPU1_SA_DQS_DP<0>
  DQS0_A_C  = M_H_CPU1_SA_DQS_DN<0>
  VSS3  = GND
  DQ4_A  = M_H_CPU1_SA_DQ<4>
  VSS4  = GND
  DQ5_A  = M_H_CPU1_SA_DQ<5>
  VSS5  = GND
  DQ8_A  = M_H_CPU1_SA_DQ<8>
  VSS6  = GND
  DQ9_A  = M_H_CPU1_SA_DQ<9>
  VSS7  = GND
  DQS1_A_T  = M_H_CPU1_SA_DQS_DP<1>
  DQS1_A_C  = M_H_CPU1_SA_DQS_DN<1>
  VSS8  = GND
  DQ12_A  = M_H_CPU1_SA_DQ<12>
  VSS9  = GND
  DQ13_A  = M_H_CPU1_SA_DQ<13>
  VSS10  = GND
  DQ16_A  = M_H_CPU1_SA_DQ<16>
  VSS11  = GND
  DQ17_A  = M_H_CPU1_SA_DQ<17>
  VSS12  = GND
  DQS2_A_T  = M_H_CPU1_SA_DQS_DP<2>
  DQS2_A_C  = M_H_CPU1_SA_DQS_DN<2>
  VSS13  = GND
  DQ20_A  = M_H_CPU1_SA_DQ<20>
  VSS14  = GND
  DQ21_A  = M_H_CPU1_SA_DQ<21>
  VSS15  = GND
  DQ24_A  = M_H_CPU1_SA_DQ<24>
  VSS16  = GND
  DQ25_A  = M_H_CPU1_SA_DQ<25>
  VSS17  = GND
  DQS3_A_T  = M_H_CPU1_SA_DQS_DP<3>
  DQS3_A_C  = M_H_CPU1_SA_DQS_DN<3>
  VSS18  = GND
  DQ28_A  = M_H_CPU1_SA_DQ<28>
  VSS19  = GND
  DQ29_A  = M_H_CPU1_SA_DQ<29>
  VSS20  = GND
  CB0_A  = M_H_CPU1_SA_CB<0>
  VSS21  = GND
  CB1_A  = M_H_CPU1_SA_CB<1>
  VSS22  = GND
  DQS4_A_T  = M_H_CPU1_SA_DQS_DP<4>
  DQS4_A_C  = M_H_CPU1_SA_DQS_DN<4>
  VSS23  = GND
  CB4_A  = M_H_CPU1_SA_CB<4>
  VSS24  = GND
  CB5_A  = M_H_CPU1_SA_CB<5>
  VSS25  = GND
  ALERT_N  = M_H_CPU1_ALERT_N
  VSS26  = GND
  CS0_A_N  = M_H_CPU1_SA_CS_N<0>
  VSS27  = GND
  CA0_A  = M_H_CPU1_SA_CA<0>
  VSS28  = GND
  CA2_A  = M_H_CPU1_SA_CA<2>
  VSS29  = GND
  CA4_A  = M_H_CPU1_SA_CA<4>
  VSS30  = GND
  CA6_A  = M_H_CPU1_SA_CA<6>
  VSS31  = GND
  PAR_A  = M_H_CPU1_SA_PAR
  VSS32  = GND
  CA0_B  = M_H_CPU1_SB_CA<0>
  VSS33  = GND
  CA2_B  = M_H_CPU1_SB_CA<2>
  VSS34  = GND
  CA4_B  = M_H_CPU1_SB_CA<4>
  VSS35  = GND
  CA6_B  = M_H_CPU1_SB_CA<6>
  VSS36  = GND
  CS0_B_N  = M_H_CPU1_SB_CS_N<0>
  VSS37  = GND
  \lbd||rsp_a_n\  = M_H_CPU1_SA_RSP<0>
  \lbs||rsp_b_n\  = M_H_CPU1_SB_RSP<0>
  VSS38  = GND
  CB4_B  = M_H_CPU1_SB_CB<4>
  VSS39  = GND
  CB5_B  = M_H_CPU1_SB_CB<5>
  VSS40  = GND
  \dqs9_b_t||tdqs9_b_t||dbi4_b_n\  = M_H_CPU1_SB_DQS_DP<9>
  \dqs9_b_c||tdqs9_b_c\  = M_H_CPU1_SB_DQS_DN<9>
  VSS41  = GND
  CB0_B  = M_H_CPU1_SB_CB<0>
  VSS42  = GND
  CB1_B  = M_H_CPU1_SB_CB<1>
  VSS43  = GND
  DQ0_B  = M_H_CPU1_SB_DQ<0>
  VSS44  = GND
  DQ1_B  = M_H_CPU1_SB_DQ<1>
  VSS45  = GND
  DQS0_B_T  = M_H_CPU1_SB_DQS_DP<0>
  DQS0_B_C  = M_H_CPU1_SB_DQS_DN<0>
  VSS46  = GND
  DQ4_B  = M_H_CPU1_SB_DQ<4>
  VSS47  = GND
  DQ5_B  = M_H_CPU1_SB_DQ<5>
  VSS48  = GND
  DQ8_B  = M_H_CPU1_SB_DQ<8>
  VSS49  = GND
  DQ9_B  = M_H_CPU1_SB_DQ<9>
  VSS50  = GND
  DQS1_B_T  = M_H_CPU1_SB_DQS_DP<1>
  DQS1_B_C  = M_H_CPU1_SB_DQS_DN<1>
  VSS51  = GND
  DQ12_B  = M_H_CPU1_SB_DQ<12>
  VSS52  = GND
  DQ13_B  = M_H_CPU1_SB_DQ<13>
  VSS53  = GND
  DQ16_B  = M_H_CPU1_SB_DQ<16>
  VSS54  = GND
  DQ17_B  = M_H_CPU1_SB_DQ<17>
  VSS55  = GND
  DQS2_B_T  = M_H_CPU1_SB_DQS_DP<2>
  DQS2_B_C  = M_H_CPU1_SB_DQS_DN<2>
  VSS56  = GND
  DQ20_B  = M_H_CPU1_SB_DQ<20>
  VSS57  = GND
  DQ21_B  = M_H_CPU1_SB_DQ<21>
  VSS58  = GND
  DQ24_B  = M_H_CPU1_SB_DQ<24>
  VSS59  = GND
  DQ25_B  = M_H_CPU1_SB_DQ<25>
  VSS60  = GND
  DQS3_B_T  = M_H_CPU1_SB_DQS_DP<3>
  DQS3_B_C  = M_H_CPU1_SB_DQS_DN<3>
  VSS61  = GND
  DQ28_B  = M_H_CPU1_SB_DQ<28>
  VSS62  = GND
  DQ29_B  = M_H_CPU1_SB_DQ<29>
  VSS63  = GND
  RFU1  = NC
  VIN_BULK1  = P12V_MEM_CPU1
  VIN_BULK2  = P12V_MEM_CPU1
  \pwr_good||fail_n\  = PWRGD_CHH_CPU1_DIMM
  HAS  = PD_CHH_CPU1_DIMM_SAA
  RFU2  = NC
  RFU3  = NC
  VSS64  = GND
  DQ2_A  = M_H_CPU1_SA_DQ<2>
  VSS65  = GND
  DQ3_A  = M_H_CPU1_SA_DQ<3>
  VSS66  = GND
  \dqs5_a_c||tdqs5_a_c||dqs5_a_t||tdqs5_a_t\  = M_H_CPU1_SA_DQS_DN<5>
  \dqs5_a_t||tdqs5_a_t\  = M_H_CPU1_SA_DQS_DP<5>
  VSS67  = GND
  DQ6_A  = M_H_CPU1_SA_DQ<6>
  VSS68  = GND
  DQ7_A  = M_H_CPU1_SA_DQ<7>
  VSS69  = GND
  DQ10_A  = M_H_CPU1_SA_DQ<10>
  VSS70  = GND
  DQ11_A  = M_H_CPU1_SA_DQ<11>
  VSS71  = GND
  \dqs6_a_c||tdqs6_a_c||dqs6_a_t||tdqs6_a_t\  = M_H_CPU1_SA_DQS_DN<6>
  \dqs6_a_t||tdqs6_a_t\  = M_H_CPU1_SA_DQS_DP<6>
  VSS72  = GND
  DQ14_A  = M_H_CPU1_SA_DQ<14>
  VSS73  = GND
  DQ15_A  = M_H_CPU1_SA_DQ<15>
  VSS74  = GND
  DQ18_A  = M_H_CPU1_SA_DQ<18>
  VSS75  = GND
  DQ19_A  = M_H_CPU1_SA_DQ<19>
  VSS76  = GND
  \dqs7_a_c||tdqs7_a_c\  = M_H_CPU1_SA_DQS_DN<7>
  \dqs7_a_t||tdqs7_a_t\  = M_H_CPU1_SA_DQS_DP<7>
  VSS77  = GND
  DQ22_A  = M_H_CPU1_SA_DQ<22>
  VSS78  = GND
  DQ23_A  = M_H_CPU1_SA_DQ<23>
  VSS79  = GND
  DQ26_A  = M_H_CPU1_SA_DQ<26>
  VSS80  = GND
  DQ27_A  = M_H_CPU1_SA_DQ<27>
  VSS81  = GND
  \dqs8_a_c||tdqs8_a_c\  = M_H_CPU1_SA_DQS_DN<8>
  \dqs8_a_t||tdqs8_a_t\  = M_H_CPU1_SA_DQS_DP<8>
  VSS82  = GND
  DQ30_A  = M_H_CPU1_SA_DQ<30>
  VSS83  = GND
  DQ31_A  = M_H_CPU1_SA_DQ<31>
  VSS84  = GND
  CB2_A  = M_H_CPU1_SA_CB<2>
  VSS85  = GND
  CB3_A  = M_H_CPU1_SA_CB<3>
  VSS86  = GND
  \dqs9_a_c||tdqs9_a_c\  = M_H_CPU1_SA_DQS_DN<9>
  \dqs9_a_t||tdqs9_a_t\  = M_H_CPU1_SA_DQS_DP<9>
  VSS87  = GND
  CB6_A  = M_H_CPU1_SA_CB<6>
  VSS88  = GND
  CB7_A  = M_H_CPU1_SA_CB<7>
  VSS89  = GND
  RESET_N  = M_H_CPU1_RESET_N
  VSS90  = GND
  CS1_A_N  = M_H_CPU1_SA_CS_N<1>
  VSS91  = GND
  CA1_A  = M_H_CPU1_SA_CA<1>
  VSS92  = GND
  CA3_A  = M_H_CPU1_SA_CA<3>
  VSS93  = GND
  CA5_A  = M_H_CPU1_SA_CA<5>
  VSS94  = GND
  CK_T  = M_H_CPU1_CLK_DP<0>
  CK_C  = M_H_CPU1_CLK_DN<0>
  VSS95  = GND
  RFU4  = NC
  CA1_B  = M_H_CPU1_SB_CA<1>
  VSS96  = GND
  CA3_B  = M_H_CPU1_SB_CA<3>
  VSS97  = GND
  CA5_B  = M_H_CPU1_SB_CA<5>
  VSS98  = GND
  PAR_B  = M_H_CPU1_SB_PAR
  VSS99  = GND
  CS1_B_N  = M_H_CPU1_SB_CS_N<1>
  VSS100  = GND
  RFU5  = NC
  RFU6  = NC
  VSS101  = GND
  CB6_B  = M_H_CPU1_SB_CB<6>
  VSS102  = GND
  CB7_B  = M_H_CPU1_SB_CB<7>
  VSS103  = GND
  DQS4_B_C  = M_H_CPU1_SB_DQS_DN<4>
  DQS4_B_T  = M_H_CPU1_SB_DQS_DP<4>
  VSS104  = GND
  CB2_B  = M_H_CPU1_SB_CB<2>
  VSS105  = GND
  CB3_B  = M_H_CPU1_SB_CB<3>
  VSS106  = GND
  DQ2_B  = M_H_CPU1_SB_DQ<2>
  VSS107  = GND
  DQ3_B  = M_H_CPU1_SB_DQ<3>
  VSS108  = GND
  \dqs5_b_c||tdqs5_b_c\  = M_H_CPU1_SB_DQS_DN<5>
  \dqs5_b_t||tdqs5_b_t\  = M_H_CPU1_SB_DQS_DP<5>
  VSS109  = GND
  DQ6_B  = M_H_CPU1_SB_DQ<6>
  VSS110  = GND
  DQ7_B  = M_H_CPU1_SB_DQ<7>
  VSS111  = GND
  DQ10_B  = M_H_CPU1_SB_DQ<10>
  VSS112  = GND
  DQ11_B  = M_H_CPU1_SB_DQ<11>
  VSS113  = GND
  \dqs6_b_c||tdqs6_b_c\  = M_H_CPU1_SB_DQS_DN<6>
  \dqs6_b_t||tdqs6_b_t\  = M_H_CPU1_SB_DQS_DP<6>
  VSS114  = GND
  DQ14_B  = M_H_CPU1_SB_DQ<14>
  VSS115  = GND
  DQ15_B  = M_H_CPU1_SB_DQ<15>
  VSS116  = GND
  DQ18_B  = M_H_CPU1_SB_DQ<18>
  VSS117  = GND
  DQ19_B  = M_H_CPU1_SB_DQ<19>
  VSS118  = GND
  \dqs7_b_c||tdqs7_b_c\  = M_H_CPU1_SB_DQS_DN<7>
  \dqs7_b_t||tdqs7_b_t\  = M_H_CPU1_SB_DQS_DP<7>
  VSS119  = GND
  DQ22_B  = M_H_CPU1_SB_DQ<22>
  VSS120  = GND
  DQ23_B  = M_H_CPU1_SB_DQ<23>
  VSS121  = GND
  DQ26_B  = M_H_CPU1_SB_DQ<26>
  VSS122  = GND
  DQ27_B  = M_H_CPU1_SB_DQ<27>
  VSS123  = GND
  \dqs8_b_c||tdqs8_b_c\  = M_H_CPU1_SB_DQS_DN<8>
  \dqs8_b_t||tdqs8_b_t\  = M_H_CPU1_SB_DQS_DP<8>
  VSS124  = GND
  DQ30_B  = M_H_CPU1_SB_DQ<30>
  VSS125  = GND
  DQ31_B  = M_H_CPU1_SB_DQ<31>
  VSS126  = GND
  G1  = GND
  G2  = GND
  G3  = GND

(kicad_pcb
	(version 20260206)
	(generator "pcbnew")
	(generator_version "10.0")
	(general
		(thickness 1.6)
		(legacy_teardrops no)
	)
	(paper "A4")
	(title_block
		(title "04192023_DAF0TMB3IC0_F0TG_MB_C_brd_V02_OCP.brd")
		(comment 1 "Grand Teton / footprint 583 of 8354 (J27), pads 1-46 of 291")
	)
	(layers
		(0 "F.Cu" signal "TOP")
		(4 "In1.Cu" signal "GND")
		(6 "In2.Cu" signal "IN1")
		(8 "In3.Cu" signal "GND1")
		(10 "In4.Cu" signal "IN2")
		(12 "In5.Cu" signal "GND2")
		(14 "In6.Cu" signal "IN3")
		(16 "In7.Cu" signal "GND3")
		(18 "In8.Cu" signal "VCC")
		(20 "In9.Cu" signal "VCC1")
		(22 "In10.Cu" signal "GND4")
		(24 "In11.Cu" signal "IN4")
		(26 "In12.Cu" signal "GND5")
		(28 "In13.Cu" signal "IN5")
		(30 "In14.Cu" signal "GND6")
		(32 "In15.Cu" signal "IN6")
		(34 "In16.Cu" signal "GND7")
		(2 "B.Cu" signal "BOTTOM")
		(9 "F.Adhes" user "F.Adhesive")
		(11 "B.Adhes" user "B.Adhesive")
		(13 "F.Paste" user "Package Geometry/Pastemask Top")
		(15 "B.Paste" user "Package Geometry/Pastemask Bottom")
		(5 "F.SilkS" user "Ref Des/Silkscreen Top")
		(7 "B.SilkS" user "Ref Des/Silkscreen Bottom")
		(1 "F.Mask" user "Board Geometry/Soldermask Top")
		(3 "B.Mask" user "Board Geometry/Soldermask Bottom")
		(17 "Dwgs.User" user "User.Drawings")
		(19 "Cmts.User" user "User.Comments")
		(21 "Eco1.User" user "User.Eco1")
		(23 "Eco2.User" user "User.Eco2")
		(25 "Edge.Cuts" user "Board Geometry/Outline")
		(27 "Margin" user)
		(31 "F.CrtYd" user "Package Geometry/Place Bound Top")
		(29 "B.CrtYd" user "Package Geometry/Place Bound Bottom")
		(35 "F.Fab" user "Ref Des/Assembly Top")
		(33 "B.Fab" user "Ref Des/Assembly Bottom")
	)
	(footprint ""
		(layer "F.Cu")
		(at 174.022004 -255.560322 180)
		(property "Reference" "J27"
			(at -2.7178 -81.857088 0)
			(unlocked yes)
			(layer "F.SilkS")
			(effects
				(font
					(size 0.7874 0.5842)
					(thickness 0.1524)
				)
			)
		)
		(property "Value" ""
			(at 0 0 180)
			(layer "F.Fab")
			(effects
				(font
					(size 1.27 1.27)
				)
			)
		)
		(duplicate_pad_numbers_are_jumpers no)
		(pad "1" smd rect
			(at -2.050034 -63.324994 90)
			(size 0.519938 1.4986)
			(layers "F.Cu" "F.Mask" "F.Paste")
			(net "P12V_MEM_CPU1")
		)
		(pad "2" smd rect
			(at -2.050034 -62.47511 90)
			(size 0.519938 1.4986)
			(layers "F.Cu" "F.Mask" "F.Paste")
			(net "Net_2354")
		)
		(pad "3" smd rect
			(at -2.050034 -61.624972 90)
			(size 0.519938 1.4986)
			(layers "F.Cu" "F.Mask" "F.Paste")
			(net "P3V3_AUX")
		)
		(pad "4" smd rect
			(at -2.050034 -60.775088 90)
			(size 0.519938 1.4986)
			(layers "F.Cu" "F.Mask" "F.Paste")
			(net "I3C_SPD_DDRH_CPU1_SCL")
		)
		(pad "5" smd rect
			(at -2.050034 -59.92495 90)
			(size 0.519938 1.4986)
			(layers "F.Cu" "F.Mask" "F.Paste")
			(net "I3C_SPD_DDRH_CPU1_SDA")
		)
		(pad "6" smd rect
			(at -2.050034 -59.075066 90)
			(size 0.519938 1.4986)
			(layers "F.Cu" "F.Mask" "F.Paste")
			(net "GND")
		)
		(pad "7" smd rect
			(at -2.050034 -58.224928 90)
			(size 0.519938 1.4986)
			(layers "F.Cu" "F.Mask" "F.Paste")
			(net "M_H_CPU1_SA_DQ<0>")
		)
		(pad "8" smd rect
			(at -2.050034 -57.375044 90)
			(size 0.519938 1.4986)
			(layers "F.Cu" "F.Mask" "F.Paste")
			(net "GND")
		)
		(pad "9" smd rect
			(at -2.050034 -56.524906 90)
			(size 0.519938 1.4986)
			(layers "F.Cu" "F.Mask" "F.Paste")
			(net "M_H_CPU1_SA_DQ<1>")
		)
		(pad "10" smd rect
			(at -2.050034 -55.675022 90)
			(size 0.519938 1.4986)
			(layers "F.Cu" "F.Mask" "F.Paste")
			(net "GND")
		)
		(pad "11" smd rect
			(at -2.050034 -54.824884 90)
			(size 0.519938 1.4986)
			(layers "F.Cu" "F.Mask" "F.Paste")
			(net "M_H_CPU1_SA_DQS_DP<0>")
		)
		(pad "12" smd rect
			(at -2.050034 -53.975 90)
			(size 0.519938 1.4986)
			(layers "F.Cu" "F.Mask" "F.Paste")
			(net "M_H_CPU1_SA_DQS_DN<0>")
		)
		(pad "13" smd rect
			(at -2.050034 -53.125116 90)
			(size 0.519938 1.4986)
			(layers "F.Cu" "F.Mask" "F.Paste")
			(net "GND")
		)
		(pad "14" smd rect
			(at -2.050034 -52.274978 90)
			(size 0.519938 1.4986)
			(layers "F.Cu" "F.Mask" "F.Paste")
			(net "M_H_CPU1_SA_DQ<4>")
		)
		(pad "15" smd rect
			(at -2.050034 -51.425094 90)
			(size 0.519938 1.4986)
			(layers "F.Cu" "F.Mask" "F.Paste")
			(net "GND")
		)
		(pad "16" smd rect
			(at -2.050034 -50.574956 90)
			(size 0.519938 1.4986)
			(layers "F.Cu" "F.Mask" "F.Paste")
			(net "M_H_CPU1_SA_DQ<5>")
		)
		(pad "17" smd rect
			(at -2.050034 -49.725072 90)
			(size 0.519938 1.4986)
			(layers "F.Cu" "F.Mask" "F.Paste")
			(net "GND")
		)
		(pad "18" smd rect
			(at -2.050034 -48.874934 90)
			(size 0.519938 1.4986)
			(layers "F.Cu" "F.Mask" "F.Paste")
			(net "M_H_CPU1_SA_DQ<8>")
		)
		(pad "19" smd rect
			(at -2.050034 -48.02505 90)
			(size 0.519938 1.4986)
			(layers "F.Cu" "F.Mask" "F.Paste")
			(net "GND")
		)
		(pad "20" smd rect
			(at -2.050034 -47.174912 90)
			(size 0.519938 1.4986)
			(layers "F.Cu" "F.Mask" "F.Paste")
			(net "M_H_CPU1_SA_DQ<9>")
		)
		(pad "21" smd rect
			(at -2.050034 -46.325028 90)
			(size 0.519938 1.4986)
			(layers "F.Cu" "F.Mask" "F.Paste")
			(net "GND")
		)
		(pad "22" smd rect
			(at -2.050034 -45.47489 90)
			(size 0.519938 1.4986)
			(layers "F.Cu" "F.Mask" "F.Paste")
			(net "M_H_CPU1_SA_DQS_DP<1>")
		)
		(pad "23" smd rect
			(at -2.050034 -44.625006 90)
			(size 0.519938 1.4986)
			(layers "F.Cu" "F.Mask" "F.Paste")
			(net "M_H_CPU1_SA_DQS_DN<1>")
		)
		(pad "24" smd rect
			(at -2.050034 -43.775122 90)
			(size 0.519938 1.4986)
			(layers "F.Cu" "F.Mask" "F.Paste")
			(net "GND")
		)
		(pad "25" smd rect
			(at -2.050034 -42.924984 90)
			(size 0.519938 1.4986)
			(layers "F.Cu" "F.Mask" "F.Paste")
			(net "M_H_CPU1_SA_DQ<12>")
		)
		(pad "26" smd rect
			(at -2.050034 -42.0751 90)
			(size 0.519938 1.4986)
			(layers "F.Cu" "F.Mask" "F.Paste")
			(net "GND")
		)
		(pad "27" smd rect
			(at -2.050034 -41.224962 90)
			(size 0.519938 1.4986)
			(layers "F.Cu" "F.Mask" "F.Paste")
			(net "M_H_CPU1_SA_DQ<13>")
		)
		(pad "28" smd rect
			(at -2.050034 -40.375078 90)
			(size 0.519938 1.4986)
			(layers "F.Cu" "F.Mask" "F.Paste")
			(net "GND")
		)
		(pad "29" smd rect
			(at -2.050034 -39.52494 90)
			(size 0.519938 1.4986)
			(layers "F.Cu" "F.Mask" "F.Paste")
			(net "M_H_CPU1_SA_DQ<16>")
		)
		(pad "30" smd rect
			(at -2.050034 -38.675056 90)
			(size 0.519938 1.4986)
			(layers "F.Cu" "F.Mask" "F.Paste")
			(net "GND")
		)
		(pad "31" smd rect
			(at -2.050034 -37.824918 90)
			(size 0.519938 1.4986)
			(layers "F.Cu" "F.Mask" "F.Paste")
			(net "M_H_CPU1_SA_DQ<17>")
		)
		(pad "32" smd rect
			(at -2.050034 -36.975034 90)
			(size 0.519938 1.4986)
			(layers "F.Cu" "F.Mask" "F.Paste")
			(net "GND")
		)
		(pad "33" smd rect
			(at -2.050034 -36.124896 90)
			(size 0.519938 1.4986)
			(layers "F.Cu" "F.Mask" "F.Paste")
			(net "M_H_CPU1_SA_DQS_DP<2>")
		)
		(pad "34" smd rect
			(at -2.050034 -35.275012 90)
			(size 0.519938 1.4986)
			(layers "F.Cu" "F.Mask" "F.Paste")
			(net "M_H_CPU1_SA_DQS_DN<2>")
		)
		(pad "35" smd rect
			(at -2.050034 -34.425128 90)
			(size 0.519938 1.4986)
			(layers "F.Cu" "F.Mask" "F.Paste")
			(net "GND")
		)
		(pad "36" smd rect
			(at -2.050034 -33.57499 90)
			(size 0.519938 1.4986)
			(layers "F.Cu" "F.Mask" "F.Paste")
			(net "M_H_CPU1_SA_DQ<20>")
		)
		(pad "37" smd rect
			(at -2.050034 -32.725106 90)
			(size 0.519938 1.4986)
			(layers "F.Cu" "F.Mask" "F.Paste")
			(net "GND")
		)
		(pad "38" smd rect
			(at -2.050034 -31.874968 90)
			(size 0.519938 1.4986)
			(layers "F.Cu" "F.Mask" "F.Paste")
			(net "M_H_CPU1_SA_DQ<21>")
		)
		(pad "39" smd rect
			(at -2.050034 -31.025084 90)
			(size 0.519938 1.4986)
			(layers "F.Cu" "F.Mask" "F.Paste")
			(net "GND")
		)
		(pad "40" smd rect
			(at -2.050034 -30.174946 90)
			(size 0.519938 1.4986)
			(layers "F.Cu" "F.Mask" "F.Paste")
			(net "M_H_CPU1_SA_DQ<24>")
		)
		(pad "41" smd rect
			(at -2.050034 -29.325062 90)
			(size 0.519938 1.4986)
			(layers "F.Cu" "F.Mask" "F.Paste")
			(net "GND")
		)
		(pad "42" smd rect
			(at -2.050034 -28.474924 90)
			(size 0.519938 1.4986)
			(layers "F.Cu" "F.Mask" "F.Paste")
			(net "M_H_CPU1_SA_DQ<25>")
		)
		(pad "43" smd rect
			(at -2.050034 -27.62504 90)
			(size 0.519938 1.4986)
			(layers "F.Cu" "F.Mask" "F.Paste")
			(net "GND")
		)
		(pad "44" smd rect
			(at -2.050034 -26.774902 90)
			(size 0.519938 1.4986)
			(layers "F.Cu" "F.Mask" "F.Paste")
			(net "M_H_CPU1_SA_DQS_DP<3>")
		)
		(pad "45" smd rect
			(at -2.050034 -25.925018 90)
			(size 0.519938 1.4986)
			(layers "F.Cu" "F.Mask" "F.Paste")
			(net "M_H_CPU1_SA_DQS_DN<3>")
		)
		(pad "46" smd rect
			(at -2.050034 -25.07488 90)
			(size 0.519938 1.4986)
			(layers "F.Cu" "F.Mask" "F.Paste")
			(net "GND")
		)
	)
)
